# T6G (Grand Teton) — schematic netlist excerpt (pin names and nets, part order shuffled) for the footprints in the layout excerpt that follows; sources: Cadence DE-HDL packaged netlist, KiCad conversion of 04192023_DAF0TMB3IC0_F0TG_MB_C_brd_V02_OCP.brd

R6220  Q_RES  10K 1% EMPTY  pkg 0402LF  page 176 : A = P3V3_AUX ; B = USB_CPU0_ADD_A2
R6078  Q_RES  0 5% CHIP  pkg 0402LF  page 85 : A = PWRGD_P3V3_AUX ; B = PWRGD_P3V3_AUX_PDB

(kicad_pcb
	(version 20260206)
	(generator "pcbnew")
	(generator_version "10.0")
	(general
		(thickness 1.6)
		(legacy_teardrops no)
	)
	(paper "A4")
	(title_block
		(title "04192023_DAF0TMB3IC0_F0TG_MB_C_brd_V02_OCP.brd")
		(comment 1 "Grand Teton / footprints 2964-2965 of 8354")
	)
	(layers
		(0 "F.Cu" signal "TOP")
		(4 "In1.Cu" signal "GND")
		(6 "In2.Cu" signal "IN1")
		(8 "In3.Cu" signal "GND1")
		(10 "In4.Cu" signal "IN2")
		(12 "In5.Cu" signal "GND2")
		(14 "In6.Cu" signal "IN3")
		(16 "In7.Cu" signal "GND3")
		(18 "In8.Cu" signal "VCC")
		(20 "In9.Cu" signal "VCC1")
		(22 "In10.Cu" signal "GND4")
		(24 "In11.Cu" signal "IN4")
		(26 "In12.Cu" signal "GND5")
		(28 "In13.Cu" signal "IN5")
		(30 "In14.Cu" signal "GND6")
		(32 "In15.Cu" signal "IN6")
		(34 "In16.Cu" signal "GND7")
		(2 "B.Cu" signal "BOTTOM")
		(9 "F.Adhes" user "F.Adhesive")
		(11 "B.Adhes" user "B.Adhesive")
		(13 "F.Paste" user "Package Geometry/Pastemask Top")
		(15 "B.Paste" user "Package Geometry/Pastemask Bottom")
		(5 "F.SilkS" user "Ref Des/Silkscreen Top")
		(7 "B.SilkS" user "Ref Des/Silkscreen Bottom")
		(1 "F.Mask" user "Board Geometry/Soldermask Top")
		(3 "B.Mask" user "Board Geometry/Soldermask Bottom")
		(17 "Dwgs.User" user "User.Drawings")
		(19 "Cmts.User" user "User.Comments")
		(21 "Eco1.User" user "User.Eco1")
		(23 "Eco2.User" user "User.Eco2")
		(25 "Edge.Cuts" user "Board Geometry/Outline")
		(27 "Margin" user)
		(31 "F.CrtYd" user "Package Geometry/Place Bound Top")
		(29 "B.CrtYd" user "Package Geometry/Place Bound Bottom")
		(35 "F.Fab" user "Ref Des/Assembly Top")
		(33 "B.Fab" user "Ref Des/Assembly Bottom")
	)
	(footprint ""
		(layer "F.Cu")
		(at 105.84561 -63.54191)
		(property "Reference" "R6220"
			(at 0 0 0)
			(layer "F.SilkS")
			(hide yes)
			(effects
				(font
					(size 1.27 1.27)
				)
			)
		)
		(property "Value" ""
			(at 0 0 0)
			(layer "F.Fab")
			(effects
				(font
					(size 1.27 1.27)
				)
			)
		)
		(duplicate_pad_numbers_are_jumpers no)
		(fp_line
			(start -0.7874 -0.4064)
			(end 0.7874 -0.4064)
			(stroke
				(width 0.1524)
				(type default)
			)
			(layer "F.SilkS")
		)
		(fp_line
			(start -0.7874 0.4064)
			(end -0.7874 -0.4064)
			(stroke
				(width 0.1524)
				(type default)
			)
			(layer "F.SilkS")
		)
		(fp_line
			(start 0.7874 -0.4064)
			(end 0.7874 0.4064)
			(stroke
				(width 0.1524)
				(type default)
			)
			(layer "F.SilkS")
		)
		(fp_line
			(start 0.7874 0.4064)
			(end -0.7874 0.4064)
			(stroke
				(width 0.1524)
				(type default)
			)
			(layer "F.SilkS")
		)
		(fp_line
			(start -0.67945 -0.305054)
			(end -0.12065 -0.305054)
			(stroke
				(width 0.1)
				(type default)
			)
			(layer "F.Fab")
		)
		(fp_line
			(start -0.67945 0.3048)
			(end -0.67945 -0.305054)
			(stroke
				(width 0.1)
				(type default)
			)
			(layer "F.Fab")
		)
		(fp_line
			(start -0.12065 -0.305054)
			(end -0.12065 -0.2794)
			(stroke
				(width 0.1)
				(type default)
			)
			(layer "F.Fab")
		)
		(fp_line
			(start -0.12065 -0.2794)
			(end 0.12065 -0.2794)
			(stroke
				(width 0.1)
				(type default)
			)
			(layer "F.Fab")
		)
		(fp_line
			(start -0.12065 0.2794)
			(end -0.12065 0.3048)
			(stroke
				(width 0.1)
				(type default)
			)
			(layer "F.Fab")
		)
		(fp_line
			(start -0.12065 0.3048)
			(end -0.67945 0.3048)
			(stroke
				(width 0.1)
				(type default)
			)
			(layer "F.Fab")
		)
		(fp_line
			(start 0.120396 0.2794)
			(end -0.12065 0.2794)
			(stroke
				(width 0.1)
				(type default)
			)
			(layer "F.Fab")
		)
		(fp_line
			(start 0.120396 0.3048)
			(end 0.120396 0.2794)
			(stroke
				(width 0.1)
				(type default)
			)
			(layer "F.Fab")
		)
		(fp_line
			(start 0.12065 -0.3048)
			(end 0.67945 -0.3048)
			(stroke
				(width 0.1)
				(type default)
			)
			(layer "F.Fab")
		)
		(fp_line
			(start 0.12065 -0.2794)
			(end 0.12065 -0.3048)
			(stroke
				(width 0.1)
				(type default)
			)
			(layer "F.Fab")
		)
		(fp_line
			(start 0.67945 -0.3048)
			(end 0.67945 0.3048)
			(stroke
				(width 0.1)
				(type default)
			)
			(layer "F.Fab")
		)
		(fp_line
			(start 0.67945 0.3048)
			(end 0.120396 0.3048)
			(stroke
				(width 0.1)
				(type default)
			)
			(layer "F.Fab")
		)
		(pad "1" smd circle
			(at -0.40005 0)
			(size 0 0)
			(layers "F.Cu" "F.Mask" "F.Paste")
			(net "P3V3_AUX")
		)
		(pad "2" smd circle
			(at 0.40005 0)
			(size 0 0)
			(layers "F.Cu" "F.Mask" "F.Paste")
			(net "USB_CPU0_ADD_A2")
		)
	)
	(footprint ""
		(layer "F.Cu")
		(at 205.203044 -109.561376)
		(property "Reference" "R6078"
			(at 0 0 0)
			(layer "F.SilkS")
			(hide yes)
			(effects
				(font
					(size 1.27 1.27)
				)
			)
		)
		(property "Value" ""
			(at 0 0 0)
			(layer "F.Fab")
			(effects
				(font
					(size 1.27 1.27)
				)
			)
		)
		(duplicate_pad_numbers_are_jumpers no)
		(fp_line
			(start -0.7874 -0.4064)
			(end 0.7874 -0.4064)
			(stroke
				(width 0.1524)
				(type default)
			)
			(layer "F.SilkS")
		)
		(fp_line
			(start -0.7874 0.4064)
			(end -0.7874 -0.4064)
			(stroke
				(width 0.1524)
				(type default)
			)
			(layer "F.SilkS")
		)
		(fp_line
			(start 0.7874 -0.4064)
			(end 0.7874 0.4064)
			(stroke
				(width 0.1524)
				(type default)
			)
			(layer "F.SilkS")
		)
		(fp_line
			(start 0.7874 0.4064)
			(end -0.7874 0.4064)
			(stroke
				(width 0.1524)
				(type default)
			)
			(layer "F.SilkS")
		)
		(fp_line
			(start -0.67945 -0.305054)
			(end -0.12065 -0.305054)
			(stroke
				(width 0.1)
				(type default)
			)
			(layer "F.Fab")
		)
		(fp_line
			(start -0.67945 0.3048)
			(end -0.67945 -0.305054)
			(stroke
				(width 0.1)
				(type default)
			)
			(layer "F.Fab")
		)
		(fp_line
			(start -0.12065 -0.305054)
			(end -0.12065 -0.2794)
			(stroke
				(width 0.1)
				(type default)
			)
			(layer "F.Fab")
		)
		(fp_line
			(start -0.12065 -0.2794)
			(end 0.12065 -0.2794)
			(stroke
				(width 0.1)
				(type default)
			)
			(layer "F.Fab")
		)
		(fp_line
			(start -0.12065 0.2794)
			(end -0.12065 0.3048)
			(stroke
				(width 0.1)
				(type default)
			)
			(layer "F.Fab")
		)
		(fp_line
			(start -0.12065 0.3048)
			(end -0.67945 0.3048)
			(stroke
				(width 0.1)
				(type default)
			)
			(layer "F.Fab")
		)
		(fp_line
			(start 0.120396 0.2794)
			(end -0.12065 0.2794)
			(stroke
				(width 0.1)
				(type default)
			)
			(layer "F.Fab")
		)
		(fp_line
			(start 0.120396 0.3048)
			(end 0.120396 0.2794)
			(stroke
				(width 0.1)
				(type default)
			)
			(layer "F.Fab")
		)
		(fp_line
			(start 0.12065 -0.3048)
			(end 0.67945 -0.3048)
			(stroke
				(width 0.1)
				(type default)
			)
			(layer "F.Fab")
		)
		(fp_line
			(start 0.12065 -0.2794)
			(end 0.12065 -0.3048)
			(stroke
				(width 0.1)
				(type default)
			)
			(layer "F.Fab")
		)
		(fp_line
			(start 0.67945 -0.3048)
			(end 0.67945 0.3048)
			(stroke
				(width 0.1)
				(type default)
			)
			(layer "F.Fab")
		)
		(fp_line
			(start 0.67945 0.3048)
			(end 0.120396 0.3048)
			(stroke
				(width 0.1)
				(type default)
			)
			(layer "F.Fab")
		)
		(pad "1" smd circle
			(at -0.40005 0)
			(size 0 0)
			(layers "F.Cu" "F.Mask" "F.Paste")
			(net "PWRGD_P3V3_AUX")
		)
		(pad "2" smd circle
			(at 0.40005 0)
			(size 0 0)
			(layers "F.Cu" "F.Mask" "F.Paste")
			(net "PWRGD_P3V3_AUX_PDB")
		)
	)
)
